# COM Express 7 Baseboard — KiCad custom design rules (.kicad_dru)
(version 1)

(rule "Via IPI"
	(constraint hole_clearance (min 0.3mm))
	(condition "(A.Type == 'Via')")
)

(rule "100Ohm_diff_GbE_inner" 
	(constraint track_width (opt 0.125mm))
	(constraint diff_pair_gap (opt 0.22mm))
	(condition "(A.NetClass == '100Ohm-diff_GbE')")
	(layer inner)
)

(rule "90Ohm_diff_USB_inner" 
	(constraint track_width (opt 0.159mm))
	(constraint diff_pair_gap (opt 0.204mm))
	(condition "(A.NetClass == '90Ohm-diff_USB')")
	(layer inner)
)

(rule "85Ohm_diff_PCIe_inner" 
	(constraint track_width (opt 0.178mm))
	(constraint diff_pair_gap (opt 0.196mm))
	(condition "(A.NetClass == '85Ohm-diff_PCIe')")
	(layer inner)
)

(rule "50Ohm_se_inner" 
	(constraint track_width (opt 0.155mm))
	(condition "(A.NetClass == '50Ohm-se')")
	(layer inner)
)

(rule "10GKR_LM_1"
	(constraint length (min 75.4mm) (max 75.5mm))
	(constraint skew (min -0.1mm) (max 0.1mm) (opt 0.0mm))
	(condition "(A.NetName == '*10GKR*')")
)

(rule "GbEMDI_LM_2"
	(constraint length (min 18.75mm) (max 18.85mm) (opt 18.8mm))
	(constraint skew (min -0.1mm) (max 0.1mm) (opt 0.0mm))
	(condition "((A.NetName == '*D*-') || (A.NetName == '*D*+')) && (A.NetClass == '100Ohm-diff_GbE')")
)

(rule "GbEMDI_LM_1"
	(constraint length (min 107.9mm) (max 108mm))
	(constraint skew (min -0.1mm) (max 0.1mm) (opt 0.0mm))
	(condition "(A.NetName == '*MDI*')")
)

(rule "SDIO_LM"
	(constraint length (min 140.6mm) (max 141.0mm) (opt 140.8mm))
	(constraint skew (min -0.1mm) (max 0.1mm) (opt 0.0mm))
	(condition "(A.NetClass == '50Ohm-se')")
)

